(kicad_pcb
	(version 20260206)
	(generator "pcbnew")
	(generator_version "10.0")
	(general
		(thickness 1.6)
		(legacy_teardrops no)
	)
	(paper "A4")
	(title_block
		(title "Bryce Canyon_SCC_16316-1_OCP.brd")
		(comment 1 "Bryce Canyon / footprint 64 of 1561 (U1), pads 819-939 of 1020")
	)
	(layers
		(0 "F.Cu" signal "TOP")
		(4 "In1.Cu" signal "L2GND")
		(6 "In2.Cu" signal "L3")
		(8 "In3.Cu" signal "L4VCC")
		(10 "In4.Cu" signal "L5VCC")
		(12 "In5.Cu" signal "L6")
		(14 "In6.Cu" signal "L7GND")
		(2 "B.Cu" signal "BOTTOM")
		(9 "F.Adhes" user "F.Adhesive")
		(11 "B.Adhes" user "B.Adhesive")
		(13 "F.Paste" user "Package Geometry/Pastemask Top")
		(15 "B.Paste" user "Package Geometry/Pastemask Bottom")
		(5 "F.SilkS" user "Ref Des/Silkscreen Top")
		(7 "B.SilkS" user "Ref Des/Silkscreen Bottom")
		(1 "F.Mask" user "Board Geometry/Soldermask Top")
		(3 "B.Mask" user "Board Geometry/Soldermask Bottom")
		(17 "Dwgs.User" user "User.Drawings")
		(19 "Cmts.User" user "User.Comments")
		(21 "Eco1.User" user "User.Eco1")
		(23 "Eco2.User" user "User.Eco2")
		(25 "Edge.Cuts" user "Board Geometry/Outline")
		(27 "Margin" user)
		(31 "F.CrtYd" user "Package Geometry/Place Bound Top")
		(29 "B.CrtYd" user "Package Geometry/Place Bound Bottom")
		(35 "F.Fab" user "Ref Des/Assembly Top")
		(33 "B.Fab" user "Ref Des/Assembly Bottom")
	)
	(footprint ""
		(layer "F.Cu")
		(at 115.000024 -67.00012)
		(property "Reference" "U1"
			(at 0 0 0)
			(layer "F.SilkS")
			(hide yes)
			(effects
				(font
					(size 1.27 1.27)
				)
			)
		)
		(property "Value" "LSISAS3X48-GP"
			(at -24.358092 -5.0292 0)
			(unlocked yes)
			(layer "F.Fab")
			(hide yes)
			(effects
				(font
					(size 1.016 1.016)
					(thickness 0.1524)
				)
			)
		)
		(property "Device Type" "BGA1020C33H83"
			(at -24.358092 -6.5532 0)
			(unlocked yes)
			(layer "F.Fab")
			(hide yes)
			(effects
				(font
					(size 1.016 1.016)
					(thickness 0.1524)
				)
			)
		)
		(duplicate_pad_numbers_are_jumpers no)
		(pad "P23" smd circle
			(at 6.500114 -2.500122)
			(size 0.4572 0.4572)
			(layers "F.Cu" "F.Mask" "F.Paste")
			(net "GND")
		)
		(pad "P24" smd circle
			(at 7.500112 -2.500122)
			(size 0.4572 0.4572)
			(layers "F.Cu" "F.Mask" "F.Paste")
			(net "GND")
		)
		(pad "P25" smd circle
			(at 8.50011 -2.500122)
			(size 0.4572 0.4572)
			(layers "F.Cu" "F.Mask" "F.Paste")
			(net "GB_VDDA")
		)
		(pad "P26" smd circle
			(at 9.500108 -2.500122)
			(size 0.4572 0.4572)
			(layers "F.Cu" "F.Mask" "F.Paste")
			(net "GND")
		)
		(pad "P27" smd circle
			(at 10.500106 -2.500122)
			(size 0.4572 0.4572)
			(layers "F.Cu" "F.Mask" "F.Paste")
			(net "PHY_DPB_TO_SCC_C_4_DN")
		)
		(pad "P28" smd circle
			(at 11.500104 -2.500122)
			(size 0.4572 0.4572)
			(layers "F.Cu" "F.Mask" "F.Paste")
			(net "PHY_DPB_TO_SCC_C_4_DP")
		)
		(pad "P29" smd circle
			(at 12.500102 -2.500122)
			(size 0.4572 0.4572)
			(layers "F.Cu" "F.Mask" "F.Paste")
			(net "GB_VDDA")
		)
		(pad "P30" smd circle
			(at 13.5001 -2.500122)
			(size 0.4572 0.4572)
			(layers "F.Cu" "F.Mask" "F.Paste")
			(net "PHY_SCC_TO_DPB_4_DN")
		)
		(pad "P31" smd circle
			(at 14.500098 -2.500122)
			(size 0.4572 0.4572)
			(layers "F.Cu" "F.Mask" "F.Paste")
			(net "PHY_SCC_TO_DPB_4_DP")
		)
		(pad "P32" smd circle
			(at 15.500096 -2.500122)
			(size 0.4572 0.4572)
			(layers "F.Cu" "F.Mask" "F.Paste")
			(net "GND")
		)
		(pad "R1" smd circle
			(at -15.500096 -1.500124)
			(size 0.4572 0.4572)
			(layers "F.Cu" "F.Mask" "F.Paste")
			(net "Net_1294")
		)
		(pad "R2" smd circle
			(at -14.500098 -1.500124)
			(size 0.4572 0.4572)
			(layers "F.Cu" "F.Mask" "F.Paste")
			(net "Net_1293")
		)
		(pad "R3" smd circle
			(at -13.5001 -1.500124)
			(size 0.4572 0.4572)
			(layers "F.Cu" "F.Mask" "F.Paste")
			(net "GND")
		)
		(pad "R4" smd circle
			(at -12.500102 -1.500124)
			(size 0.4572 0.4572)
			(layers "F.Cu" "F.Mask" "F.Paste")
			(net "Net_1292")
		)
		(pad "R5" smd circle
			(at -11.500104 -1.500124)
			(size 0.4572 0.4572)
			(layers "F.Cu" "F.Mask" "F.Paste")
			(net "GND")
		)
		(pad "R6" smd circle
			(at -10.500106 -1.500124)
			(size 0.4572 0.4572)
			(layers "F.Cu" "F.Mask" "F.Paste")
			(net "Net_1238")
		)
		(pad "R7" smd circle
			(at -9.500108 -1.500124)
			(size 0.4572 0.4572)
			(layers "F.Cu" "F.Mask" "F.Paste")
			(net "GND")
		)
		(pad "R8" smd circle
			(at -8.50011 -1.500124)
			(size 0.4572 0.4572)
			(layers "F.Cu" "F.Mask" "F.Paste")
			(net "VDDIO_DDR")
		)
		(pad "R9" smd circle
			(at -7.500112 -1.500124)
			(size 0.4572 0.4572)
			(layers "F.Cu" "F.Mask" "F.Paste")
			(net "GND")
		)
		(pad "R10" smd circle
			(at -6.500114 -1.500124)
			(size 0.4572 0.4572)
			(layers "F.Cu" "F.Mask" "F.Paste")
			(net "VDDIO_DDR")
		)
		(pad "R11" smd circle
			(at -5.500116 -1.500124)
			(size 0.4572 0.4572)
			(layers "F.Cu" "F.Mask" "F.Paste")
			(net "GND")
		)
		(pad "R12" smd circle
			(at -4.500118 -1.500124)
			(size 0.4572 0.4572)
			(layers "F.Cu" "F.Mask" "F.Paste")
			(net "P0V9")
		)
		(pad "R13" smd circle
			(at -3.50012 -1.500124)
			(size 0.4572 0.4572)
			(layers "F.Cu" "F.Mask" "F.Paste")
			(net "GND")
		)
		(pad "R14" smd circle
			(at -2.500122 -1.500124)
			(size 0.4572 0.4572)
			(layers "F.Cu" "F.Mask" "F.Paste")
			(net "P0V9")
		)
		(pad "R15" smd circle
			(at -1.500124 -1.500124)
			(size 0.4572 0.4572)
			(layers "F.Cu" "F.Mask" "F.Paste")
			(net "GND")
		)
		(pad "R16" smd circle
			(at -0.500126 -1.500124)
			(size 0.4572 0.4572)
			(layers "F.Cu" "F.Mask" "F.Paste")
			(net "P0V9")
		)
		(pad "R17" smd circle
			(at 0.500126 -1.500124)
			(size 0.4572 0.4572)
			(layers "F.Cu" "F.Mask" "F.Paste")
			(net "GND")
		)
		(pad "R18" smd circle
			(at 1.500124 -1.500124)
			(size 0.4572 0.4572)
			(layers "F.Cu" "F.Mask" "F.Paste")
			(net "P0V9")
		)
		(pad "R19" smd circle
			(at 2.500122 -1.500124)
			(size 0.4572 0.4572)
			(layers "F.Cu" "F.Mask" "F.Paste")
			(net "GND")
		)
		(pad "R20" smd circle
			(at 3.50012 -1.500124)
			(size 0.4572 0.4572)
			(layers "F.Cu" "F.Mask" "F.Paste")
			(net "P0V9")
		)
		(pad "R21" smd circle
			(at 4.500118 -1.500124)
			(size 0.4572 0.4572)
			(layers "F.Cu" "F.Mask" "F.Paste")
			(net "GND")
		)
		(pad "R22" smd circle
			(at 5.500116 -1.500124)
			(size 0.4572 0.4572)
			(layers "F.Cu" "F.Mask" "F.Paste")
			(net "GB_VDDH")
		)
		(pad "R23" smd circle
			(at 6.500114 -1.500124)
			(size 0.4572 0.4572)
			(layers "F.Cu" "F.Mask" "F.Paste")
			(net "GND")
		)
		(pad "R24" smd circle
			(at 7.500112 -1.500124)
			(size 0.4572 0.4572)
			(layers "F.Cu" "F.Mask" "F.Paste")
			(net "GB_VDDA")
		)
		(pad "R25" smd circle
			(at 8.50011 -1.500124)
			(size 0.4572 0.4572)
			(layers "F.Cu" "F.Mask" "F.Paste")
			(net "GND")
		)
		(pad "R26" smd circle
			(at 9.500108 -1.500124)
			(size 0.4572 0.4572)
			(layers "F.Cu" "F.Mask" "F.Paste")
			(net "GB_VDDA")
		)
		(pad "R27" smd circle
			(at 10.500106 -1.500124)
			(size 0.4572 0.4572)
			(layers "F.Cu" "F.Mask" "F.Paste")
			(net "PHY_DPB_TO_SCC_C_3_DN")
		)
		(pad "R28" smd circle
			(at 11.500104 -1.500124)
			(size 0.4572 0.4572)
			(layers "F.Cu" "F.Mask" "F.Paste")
			(net "PHY_DPB_TO_SCC_C_3_DP")
		)
		(pad "R29" smd circle
			(at 12.500102 -1.500124)
			(size 0.4572 0.4572)
			(layers "F.Cu" "F.Mask" "F.Paste")
			(net "GND")
		)
		(pad "R30" smd circle
			(at 13.5001 -1.500124)
			(size 0.4572 0.4572)
			(layers "F.Cu" "F.Mask" "F.Paste")
			(net "GB_VDDA")
		)
		(pad "R31" smd circle
			(at 14.500098 -1.500124)
			(size 0.4572 0.4572)
			(layers "F.Cu" "F.Mask" "F.Paste")
			(net "PHY_SCC_TO_DPB_3_DN")
		)
		(pad "R32" smd circle
			(at 15.500096 -1.500124)
			(size 0.4572 0.4572)
			(layers "F.Cu" "F.Mask" "F.Paste")
			(net "PHY_SCC_TO_DPB_3_DP")
		)
		(pad "T1" smd circle
			(at -15.500096 -0.500126)
			(size 0.4572 0.4572)
			(layers "F.Cu" "F.Mask" "F.Paste")
			(net "Net_1291")
		)
		(pad "T2" smd circle
			(at -14.500098 -0.500126)
			(size 0.4572 0.4572)
			(layers "F.Cu" "F.Mask" "F.Paste")
			(net "VDDIO_DDR")
		)
		(pad "T3" smd circle
			(at -13.5001 -0.500126)
			(size 0.4572 0.4572)
			(layers "F.Cu" "F.Mask" "F.Paste")
			(net "Net_1290")
		)
		(pad "T4" smd circle
			(at -12.500102 -0.500126)
			(size 0.4572 0.4572)
			(layers "F.Cu" "F.Mask" "F.Paste")
			(net "VDDIO_DDR")
		)
		(pad "T5" smd circle
			(at -11.500104 -0.500126)
			(size 0.4572 0.4572)
			(layers "F.Cu" "F.Mask" "F.Paste")
			(net "Net_1289")
		)
		(pad "T6" smd circle
			(at -10.500106 -0.500126)
			(size 0.4572 0.4572)
			(layers "F.Cu" "F.Mask" "F.Paste")
			(net "GND")
		)
		(pad "T7" smd circle
			(at -9.500108 -0.500126)
			(size 0.4572 0.4572)
			(layers "F.Cu" "F.Mask" "F.Paste")
			(net "VDDIO_DDR")
		)
		(pad "T8" smd circle
			(at -8.50011 -0.500126)
			(size 0.4572 0.4572)
			(layers "F.Cu" "F.Mask" "F.Paste")
			(net "GND")
		)
		(pad "T9" smd circle
			(at -7.500112 -0.500126)
			(size 0.4572 0.4572)
			(layers "F.Cu" "F.Mask" "F.Paste")
			(net "VDDIO_DDR")
		)
		(pad "T10" smd circle
			(at -6.500114 -0.500126)
			(size 0.4572 0.4572)
			(layers "F.Cu" "F.Mask" "F.Paste")
			(net "GND")
		)
		(pad "T11" smd circle
			(at -5.500116 -0.500126)
			(size 0.4572 0.4572)
			(layers "F.Cu" "F.Mask" "F.Paste")
			(net "VDDIO_DDR")
		)
		(pad "T12" smd circle
			(at -4.500118 -0.500126)
			(size 0.4572 0.4572)
			(layers "F.Cu" "F.Mask" "F.Paste")
			(net "GND")
		)
		(pad "T13" smd circle
			(at -3.50012 -0.500126)
			(size 0.4572 0.4572)
			(layers "F.Cu" "F.Mask" "F.Paste")
			(net "P0V9")
		)
		(pad "T14" smd circle
			(at -2.500122 -0.500126)
			(size 0.4572 0.4572)
			(layers "F.Cu" "F.Mask" "F.Paste")
			(net "GND")
		)
		(pad "T15" smd circle
			(at -1.500124 -0.500126)
			(size 0.4572 0.4572)
			(layers "F.Cu" "F.Mask" "F.Paste")
			(net "P0V9")
		)
		(pad "T16" smd circle
			(at -0.500126 -0.500126)
			(size 0.4572 0.4572)
			(layers "F.Cu" "F.Mask" "F.Paste")
			(net "GND")
		)
		(pad "T17" smd circle
			(at 0.500126 -0.500126)
			(size 0.4572 0.4572)
			(layers "F.Cu" "F.Mask" "F.Paste")
			(net "P0V9")
		)
		(pad "T18" smd circle
			(at 1.500124 -0.500126)
			(size 0.4572 0.4572)
			(layers "F.Cu" "F.Mask" "F.Paste")
			(net "GND")
		)
		(pad "T19" smd circle
			(at 2.500122 -0.500126)
			(size 0.4572 0.4572)
			(layers "F.Cu" "F.Mask" "F.Paste")
			(net "P0V9")
		)
		(pad "T20" smd circle
			(at 3.50012 -0.500126)
			(size 0.4572 0.4572)
			(layers "F.Cu" "F.Mask" "F.Paste")
			(net "GND")
		)
		(pad "T21" smd circle
			(at 4.500118 -0.500126)
			(size 0.4572 0.4572)
			(layers "F.Cu" "F.Mask" "F.Paste")
			(net "GND")
		)
		(pad "T22" smd circle
			(at 5.500116 -0.500126)
			(size 0.4572 0.4572)
			(layers "F.Cu" "F.Mask" "F.Paste")
			(net "GB_VDDH")
		)
		(pad "T23" smd circle
			(at 6.500114 -0.500126)
			(size 0.4572 0.4572)
			(layers "F.Cu" "F.Mask" "F.Paste")
			(net "GND")
		)
		(pad "T24" smd circle
			(at 7.500112 -0.500126)
			(size 0.4572 0.4572)
			(layers "F.Cu" "F.Mask" "F.Paste")
			(net "GND")
		)
		(pad "T25" smd circle
			(at 8.50011 -0.500126)
			(size 0.4572 0.4572)
			(layers "F.Cu" "F.Mask" "F.Paste")
			(net "GB_VDDA")
		)
		(pad "T26" smd circle
			(at 9.500108 -0.500126)
			(size 0.4572 0.4572)
			(layers "F.Cu" "F.Mask" "F.Paste")
			(net "GND")
		)
		(pad "T27" smd circle
			(at 10.500106 -0.500126)
			(size 0.4572 0.4572)
			(layers "F.Cu" "F.Mask" "F.Paste")
			(net "PHY_DPB_TO_SCC_C_2_DN")
		)
		(pad "T28" smd circle
			(at 11.500104 -0.500126)
			(size 0.4572 0.4572)
			(layers "F.Cu" "F.Mask" "F.Paste")
			(net "PHY_DPB_TO_SCC_C_2_DP")
		)
		(pad "T29" smd circle
			(at 12.500102 -0.500126)
			(size 0.4572 0.4572)
			(layers "F.Cu" "F.Mask" "F.Paste")
			(net "GB_VDDA")
		)
		(pad "T30" smd circle
			(at 13.5001 -0.500126)
			(size 0.4572 0.4572)
			(layers "F.Cu" "F.Mask" "F.Paste")
			(net "PHY_SCC_TO_DPB_2_DN")
		)
		(pad "T31" smd circle
			(at 14.500098 -0.500126)
			(size 0.4572 0.4572)
			(layers "F.Cu" "F.Mask" "F.Paste")
			(net "PHY_SCC_TO_DPB_2_DP")
		)
		(pad "T32" smd circle
			(at 15.500096 -0.500126)
			(size 0.4572 0.4572)
			(layers "F.Cu" "F.Mask" "F.Paste")
			(net "GND")
		)
		(pad "U1" smd circle
			(at -15.500096 0.500126)
			(size 0.4572 0.4572)
			(layers "F.Cu" "F.Mask" "F.Paste")
			(net "Net_1288")
		)
		(pad "U2" smd circle
			(at -14.500098 0.500126)
			(size 0.4572 0.4572)
			(layers "F.Cu" "F.Mask" "F.Paste")
			(net "Net_1287")
		)
		(pad "U3" smd circle
			(at -13.5001 0.500126)
			(size 0.4572 0.4572)
			(layers "F.Cu" "F.Mask" "F.Paste")
			(net "GND")
		)
		(pad "U4" smd circle
			(at -12.500102 0.500126)
			(size 0.4572 0.4572)
			(layers "F.Cu" "F.Mask" "F.Paste")
			(net "Net_1286")
		)
		(pad "U5" smd circle
			(at -11.500104 0.500126)
			(size 0.4572 0.4572)
			(layers "F.Cu" "F.Mask" "F.Paste")
			(net "GND")
		)
		(pad "U6" smd circle
			(at -10.500106 0.500126)
			(size 0.4572 0.4572)
			(layers "F.Cu" "F.Mask" "F.Paste")
			(net "DDR_BZ")
		)
		(pad "U7" smd circle
			(at -9.500108 0.500126)
			(size 0.4572 0.4572)
			(layers "F.Cu" "F.Mask" "F.Paste")
			(net "GND")
		)
		(pad "U8" smd circle
			(at -8.50011 0.500126)
			(size 0.4572 0.4572)
			(layers "F.Cu" "F.Mask" "F.Paste")
			(net "SYSPLL_VDDA09")
		)
		(pad "U9" smd circle
			(at -7.500112 0.500126)
			(size 0.4572 0.4572)
			(layers "F.Cu" "F.Mask" "F.Paste")
			(net "GND")
		)
		(pad "U10" smd circle
			(at -6.500114 0.500126)
			(size 0.4572 0.4572)
			(layers "F.Cu" "F.Mask" "F.Paste")
			(net "GND")
		)
		(pad "U11" smd circle
			(at -5.500116 0.500126)
			(size 0.4572 0.4572)
			(layers "F.Cu" "F.Mask" "F.Paste")
			(net "GND")
		)
		(pad "U12" smd circle
			(at -4.500118 0.500126)
			(size 0.4572 0.4572)
			(layers "F.Cu" "F.Mask" "F.Paste")
			(net "P0V9")
		)
		(pad "U13" smd circle
			(at -3.50012 0.500126)
			(size 0.4572 0.4572)
			(layers "F.Cu" "F.Mask" "F.Paste")
			(net "GND")
		)
		(pad "U14" smd circle
			(at -2.500122 0.500126)
			(size 0.4572 0.4572)
			(layers "F.Cu" "F.Mask" "F.Paste")
			(net "P0V9")
		)
		(pad "U15" smd circle
			(at -1.500124 0.500126)
			(size 0.4572 0.4572)
			(layers "F.Cu" "F.Mask" "F.Paste")
			(net "GND")
		)
		(pad "U16" smd circle
			(at -0.500126 0.500126)
			(size 0.4572 0.4572)
			(layers "F.Cu" "F.Mask" "F.Paste")
			(net "P0V9")
		)
		(pad "U17" smd circle
			(at 0.500126 0.500126)
			(size 0.4572 0.4572)
			(layers "F.Cu" "F.Mask" "F.Paste")
			(net "GND")
		)
		(pad "U18" smd circle
			(at 1.500124 0.500126)
			(size 0.4572 0.4572)
			(layers "F.Cu" "F.Mask" "F.Paste")
			(net "P0V9")
		)
		(pad "U19" smd circle
			(at 2.500122 0.500126)
			(size 0.4572 0.4572)
			(layers "F.Cu" "F.Mask" "F.Paste")
			(net "GND")
		)
		(pad "U20" smd circle
			(at 3.50012 0.500126)
			(size 0.4572 0.4572)
			(layers "F.Cu" "F.Mask" "F.Paste")
			(net "P0V9")
		)
		(pad "U21" smd circle
			(at 4.500118 0.500126)
			(size 0.4572 0.4572)
			(layers "F.Cu" "F.Mask" "F.Paste")
			(net "GND")
		)
		(pad "U22" smd circle
			(at 5.500116 0.500126)
			(size 0.4572 0.4572)
			(layers "F.Cu" "F.Mask" "F.Paste")
			(net "GB_VDDH")
		)
		(pad "U23" smd circle
			(at 6.500114 0.500126)
			(size 0.4572 0.4572)
			(layers "F.Cu" "F.Mask" "F.Paste")
			(net "GND")
		)
		(pad "U24" smd circle
			(at 7.500112 0.500126)
			(size 0.4572 0.4572)
			(layers "F.Cu" "F.Mask" "F.Paste")
			(net "GB_VDDA")
		)
		(pad "U25" smd circle
			(at 8.50011 0.500126)
			(size 0.4572 0.4572)
			(layers "F.Cu" "F.Mask" "F.Paste")
			(net "GND")
		)
		(pad "U26" smd circle
			(at 9.500108 0.500126)
			(size 0.4572 0.4572)
			(layers "F.Cu" "F.Mask" "F.Paste")
			(net "GB_VDDA")
		)
		(pad "U27" smd circle
			(at 10.500106 0.500126)
			(size 0.4572 0.4572)
			(layers "F.Cu" "F.Mask" "F.Paste")
			(net "PHY_DPB_TO_SCC_C_1_DN")
		)
		(pad "U28" smd circle
			(at 11.500104 0.500126)
			(size 0.4572 0.4572)
			(layers "F.Cu" "F.Mask" "F.Paste")
			(net "PHY_DPB_TO_SCC_C_1_DP")
		)
		(pad "U29" smd circle
			(at 12.500102 0.500126)
			(size 0.4572 0.4572)
			(layers "F.Cu" "F.Mask" "F.Paste")
			(net "GND")
		)
		(pad "U30" smd circle
			(at 13.5001 0.500126)
			(size 0.4572 0.4572)
			(layers "F.Cu" "F.Mask" "F.Paste")
			(net "GB_VDDA")
		)
		(pad "U31" smd circle
			(at 14.500098 0.500126)
			(size 0.4572 0.4572)
			(layers "F.Cu" "F.Mask" "F.Paste")
			(net "PHY_SCC_TO_DPB_1_DN")
		)
		(pad "U32" smd circle
			(at 15.500096 0.500126)
			(size 0.4572 0.4572)
			(layers "F.Cu" "F.Mask" "F.Paste")
			(net "PHY_SCC_TO_DPB_1_DP")
		)
		(pad "V1" smd circle
			(at -15.500096 1.500124)
			(size 0.4572 0.4572)
			(layers "F.Cu" "F.Mask" "F.Paste")
			(net "Net_1285")
		)
		(pad "V2" smd circle
			(at -14.500098 1.500124)
			(size 0.4572 0.4572)
			(layers "F.Cu" "F.Mask" "F.Paste")
			(net "VDDIO_DDR")
		)
		(pad "V3" smd circle
			(at -13.5001 1.500124)
			(size 0.4572 0.4572)
			(layers "F.Cu" "F.Mask" "F.Paste")
			(net "Net_1284")
		)
		(pad "V4" smd circle
			(at -12.500102 1.500124)
			(size 0.4572 0.4572)
			(layers "F.Cu" "F.Mask" "F.Paste")
			(net "VDDIO_DDR")
		)
		(pad "V5" smd circle
			(at -11.500104 1.500124)
			(size 0.4572 0.4572)
			(layers "F.Cu" "F.Mask" "F.Paste")
			(net "Net_1283")
		)
		(pad "V6" smd circle
			(at -10.500106 1.500124)
			(size 0.4572 0.4572)
			(layers "F.Cu" "F.Mask" "F.Paste")
			(net "GND")
		)
		(pad "V7" smd circle
			(at -9.500108 1.500124)
			(size 0.4572 0.4572)
			(layers "F.Cu" "F.Mask" "F.Paste")
			(net "SYSPLL_VDDA18")
		)
		(pad "V8" smd circle
			(at -8.50011 1.500124)
			(size 0.4572 0.4572)
			(layers "F.Cu" "F.Mask" "F.Paste")
			(net "GND")
		)
		(pad "V9" smd circle
			(at -7.500112 1.500124)
			(size 0.4572 0.4572)
			(layers "F.Cu" "F.Mask" "F.Paste")
			(net "PLLDDR_VDDA18")
		)
		(pad "V10" smd circle
			(at -6.500114 1.500124)
			(size 0.4572 0.4572)
			(layers "F.Cu" "F.Mask" "F.Paste")
			(net "GND")
		)
		(pad "V11" smd circle
			(at -5.500116 1.500124)
			(size 0.4572 0.4572)
			(layers "F.Cu" "F.Mask" "F.Paste")
			(net "P1V8_E")
		)
		(pad "V12" smd circle
			(at -4.500118 1.500124)
			(size 0.4572 0.4572)
			(layers "F.Cu" "F.Mask" "F.Paste")
			(net "GND")
		)
		(pad "V13" smd circle
			(at -3.50012 1.500124)
			(size 0.4572 0.4572)
			(layers "F.Cu" "F.Mask" "F.Paste")
			(net "P0V9")
		)
		(pad "V14" smd circle
			(at -2.500122 1.500124)
			(size 0.4572 0.4572)
			(layers "F.Cu" "F.Mask" "F.Paste")
			(net "GND")
		)
		(pad "V15" smd circle
			(at -1.500124 1.500124)
			(size 0.4572 0.4572)
			(layers "F.Cu" "F.Mask" "F.Paste")
			(net "P0V9")
		)
	)
)
